# S9S_MB_2U (Grand Teton) — schematic netlist excerpt (pin names and nets, part order shuffled) for the footprints in the layout excerpt that follows; sources: Cadence DE-HDL packaged netlist, KiCad conversion of 03242023_DA0F0TMBIJ0_F0T_Motherboard_J_brd_V01_OCP.brd

R2210  Q_RES  0 5% CHIP  pkg 0402LF  page 236 : A = SMB_S3M_CPU1_3V3AUX_SDA_R ; B = SMB_S3M_CPU1_3V3AUX_SDA
C446  Q_CAP  22UF 4V 20% X6S  pkg C0402  page 77 : A = PVCCFA_EHV_CPU1 ; B = GND

(kicad_pcb
	(version 20260206)
	(generator "pcbnew")
	(generator_version "10.0")
	(general
		(thickness 1.6)
		(legacy_teardrops no)
	)
	(paper "A4")
	(title_block
		(title "03242023_DA0F0TMBIJ0_F0T_Motherboard_J_brd_V01_OCP.brd")
		(comment 1 "Grand Teton / footprints 2521-2522 of 6105")
	)
	(layers
		(0 "F.Cu" signal "TOP")
		(4 "In1.Cu" signal "GND")
		(6 "In2.Cu" signal "IN1")
		(8 "In3.Cu" signal "GND1")
		(10 "In4.Cu" signal "IN2")
		(12 "In5.Cu" signal "GND2")
		(14 "In6.Cu" signal "IN3")
		(16 "In7.Cu" signal "GND3")
		(18 "In8.Cu" signal "VCC")
		(20 "In9.Cu" signal "VCC1")
		(22 "In10.Cu" signal "GND4")
		(24 "In11.Cu" signal "IN4")
		(26 "In12.Cu" signal "GND5")
		(28 "In13.Cu" signal "IN5")
		(30 "In14.Cu" signal "GND6")
		(32 "In15.Cu" signal "IN6")
		(34 "In16.Cu" signal "GND7")
		(2 "B.Cu" signal "BOTTOM")
		(9 "F.Adhes" user "F.Adhesive")
		(11 "B.Adhes" user "B.Adhesive")
		(13 "F.Paste" user "Package Geometry/Pastemask Top")
		(15 "B.Paste" user "Package Geometry/Pastemask Bottom")
		(5 "F.SilkS" user "Ref Des/Silkscreen Top")
		(7 "B.SilkS" user "Ref Des/Silkscreen Bottom")
		(1 "F.Mask" user "Board Geometry/Soldermask Top")
		(3 "B.Mask" user "Board Geometry/Soldermask Bottom")
		(17 "Dwgs.User" user "User.Drawings")
		(19 "Cmts.User" user "User.Comments")
		(21 "Eco1.User" user "User.Eco1")
		(23 "Eco2.User" user "User.Eco2")
		(25 "Edge.Cuts" user "Board Geometry/Outline")
		(27 "Margin" user)
		(31 "F.CrtYd" user "Package Geometry/Place Bound Top")
		(29 "B.CrtYd" user "Package Geometry/Place Bound Bottom")
		(35 "F.Fab" user "Ref Des/Assembly Top")
		(33 "B.Fab" user "Ref Des/Assembly Bottom")
	)
	(footprint ""
		(layer "F.Cu")
		(at 104.352852 -256.6543 -90)
		(property "Reference" "C446"
			(at 0 0 270)
			(layer "F.SilkS")
			(hide yes)
			(effects
				(font
					(size 1.27 1.27)
				)
			)
		)
		(property "Value" ""
			(at 0 0 270)
			(layer "F.Fab")
			(effects
				(font
					(size 1.27 1.27)
				)
			)
		)
		(duplicate_pad_numbers_are_jumpers no)
		(fp_line
			(start -0.7874 0.4064)
			(end -0.7874 -0.4064)
			(stroke
				(width 0.1524)
				(type default)
			)
			(layer "F.SilkS")
		)
		(fp_line
			(start 0.7874 0.4064)
			(end -0.7874 0.4064)
			(stroke
				(width 0.1524)
				(type default)
			)
			(layer "F.SilkS")
		)
		(fp_line
			(start -0.7874 -0.4064)
			(end 0.7874 -0.4064)
			(stroke
				(width 0.1524)
				(type default)
			)
			(layer "F.SilkS")
		)
		(fp_line
			(start 0.7874 -0.4064)
			(end 0.7874 0.4064)
			(stroke
				(width 0.1524)
				(type default)
			)
			(layer "F.SilkS")
		)
		(fp_line
			(start -0.67945 0.3048)
			(end -0.67945 -0.305054)
			(stroke
				(width 0.1)
				(type default)
			)
			(layer "F.Fab")
		)
		(fp_line
			(start -0.12065 0.3048)
			(end -0.67945 0.3048)
			(stroke
				(width 0.1)
				(type default)
			)
			(layer "F.Fab")
		)
		(fp_line
			(start 0.120396 0.3048)
			(end 0.120396 0.2794)
			(stroke
				(width 0.1)
				(type default)
			)
			(layer "F.Fab")
		)
		(fp_line
			(start 0.67945 0.3048)
			(end 0.120396 0.3048)
			(stroke
				(width 0.1)
				(type default)
			)
			(layer "F.Fab")
		)
		(fp_line
			(start -0.12065 0.2794)
			(end -0.12065 0.3048)
			(stroke
				(width 0.1)
				(type default)
			)
			(layer "F.Fab")
		)
		(fp_line
			(start 0.120396 0.2794)
			(end -0.12065 0.2794)
			(stroke
				(width 0.1)
				(type default)
			)
			(layer "F.Fab")
		)
		(fp_line
			(start -0.12065 -0.2794)
			(end 0.12065 -0.2794)
			(stroke
				(width 0.1)
				(type default)
			)
			(layer "F.Fab")
		)
		(fp_line
			(start 0.12065 -0.2794)
			(end 0.12065 -0.3048)
			(stroke
				(width 0.1)
				(type default)
			)
			(layer "F.Fab")
		)
		(fp_line
			(start 0.12065 -0.3048)
			(end 0.67945 -0.3048)
			(stroke
				(width 0.1)
				(type default)
			)
			(layer "F.Fab")
		)
		(fp_line
			(start 0.67945 -0.3048)
			(end 0.67945 0.3048)
			(stroke
				(width 0.1)
				(type default)
			)
			(layer "F.Fab")
		)
		(fp_line
			(start -0.67945 -0.305054)
			(end -0.12065 -0.305054)
			(stroke
				(width 0.1)
				(type default)
			)
			(layer "F.Fab")
		)
		(fp_line
			(start -0.12065 -0.305054)
			(end -0.12065 -0.2794)
			(stroke
				(width 0.1)
				(type default)
			)
			(layer "F.Fab")
		)
		(pad "1" smd circle
			(at -0.40005 0 270)
			(size 0 0)
			(layers "F.Cu" "F.Mask" "F.Paste")
			(net "PVCCFA_EHV_CPU1")
		)
		(pad "2" smd circle
			(at 0.40005 0 270)
			(size 0 0)
			(layers "F.Cu" "F.Mask" "F.Paste")
			(net "GND")
		)
	)
	(footprint ""
		(layer "F.Cu")
		(at 162.34283 -78.984348)
		(property "Reference" "R2210"
			(at 0 0 0)
			(layer "F.SilkS")
			(hide yes)
			(effects
				(font
					(size 1.27 1.27)
				)
			)
		)
		(property "Value" ""
			(at 0 0 0)
			(layer "F.Fab")
			(effects
				(font
					(size 1.27 1.27)
				)
			)
		)
		(duplicate_pad_numbers_are_jumpers no)
		(fp_line
			(start -0.7874 -0.4064)
			(end 0.7874 -0.4064)
			(stroke
				(width 0.1524)
				(type default)
			)
			(layer "F.SilkS")
		)
		(fp_line
			(start -0.7874 0.4064)
			(end -0.7874 -0.4064)
			(stroke
				(width 0.1524)
				(type default)
			)
			(layer "F.SilkS")
		)
		(fp_line
			(start 0.7874 -0.4064)
			(end 0.7874 0.4064)
			(stroke
				(width 0.1524)
				(type default)
			)
			(layer "F.SilkS")
		)
		(fp_line
			(start 0.7874 0.4064)
			(end -0.7874 0.4064)
			(stroke
				(width 0.1524)
				(type default)
			)
			(layer "F.SilkS")
		)
		(fp_line
			(start -0.67945 -0.305054)
			(end -0.12065 -0.305054)
			(stroke
				(width 0.1)
				(type default)
			)
			(layer "F.Fab")
		)
		(fp_line
			(start -0.67945 0.3048)
			(end -0.67945 -0.305054)
			(stroke
				(width 0.1)
				(type default)
			)
			(layer "F.Fab")
		)
		(fp_line
			(start -0.12065 -0.305054)
			(end -0.12065 -0.2794)
			(stroke
				(width 0.1)
				(type default)
			)
			(layer "F.Fab")
		)
		(fp_line
			(start -0.12065 -0.2794)
			(end 0.12065 -0.2794)
			(stroke
				(width 0.1)
				(type default)
			)
			(layer "F.Fab")
		)
		(fp_line
			(start -0.12065 0.2794)
			(end -0.12065 0.3048)
			(stroke
				(width 0.1)
				(type default)
			)
			(layer "F.Fab")
		)
		(fp_line
			(start -0.12065 0.3048)
			(end -0.67945 0.3048)
			(stroke
				(width 0.1)
				(type default)
			)
			(layer "F.Fab")
		)
		(fp_line
			(start 0.120396 0.2794)
			(end -0.12065 0.2794)
			(stroke
				(width 0.1)
				(type default)
			)
			(layer "F.Fab")
		)
		(fp_line
			(start 0.120396 0.3048)
			(end 0.120396 0.2794)
			(stroke
				(width 0.1)
				(type default)
			)
			(layer "F.Fab")
		)
		(fp_line
			(start 0.12065 -0.3048)
			(end 0.67945 -0.3048)
			(stroke
				(width 0.1)
				(type default)
			)
			(layer "F.Fab")
		)
		(fp_line
			(start 0.12065 -0.2794)
			(end 0.12065 -0.3048)
			(stroke
				(width 0.1)
				(type default)
			)
			(layer "F.Fab")
		)
		(fp_line
			(start 0.67945 -0.3048)
			(end 0.67945 0.3048)
			(stroke
				(width 0.1)
				(type default)
			)
			(layer "F.Fab")
		)
		(fp_line
			(start 0.67945 0.3048)
			(end 0.120396 0.3048)
			(stroke
				(width 0.1)
				(type default)
			)
			(layer "F.Fab")
		)
		(pad "1" smd circle
			(at -0.40005 0)
			(size 0 0)
			(layers "F.Cu" "F.Mask" "F.Paste")
			(net "SMB_S3M_CPU1_3V3AUX_SDA_R")
		)
		(pad "2" smd circle
			(at 0.40005 0)
			(size 0 0)
			(layers "F.Cu" "F.Mask" "F.Paste")
			(net "SMB_S3M_CPU1_3V3AUX_SDA")
		)
	)
)
